(kicad_pcb
	(version 20260206)
	(generator "pcbnew")
	(generator_version "10.0")
	(general
		(thickness 1.6)
		(legacy_teardrops no)
	)
	(paper "A4")
	(title_block
		(title "01162023_DA0F0TEBIF0_F0T_Expander_BD_F_brd_V02_OCP.brd")
		(comment 1 "Grand Teton / footprints 5910-5916 of 9728")
	)
	(layers
		(0 "F.Cu" signal "TOP")
		(4 "In1.Cu" signal "GND")
		(6 "In2.Cu" signal "VCC")
		(8 "In3.Cu" signal "VCC1")
		(10 "In4.Cu" signal "GND1")
		(12 "In5.Cu" signal "IN1")
		(14 "In6.Cu" signal "GND2")
		(16 "In7.Cu" signal "IN2")
		(18 "In8.Cu" signal "GND3")
		(20 "In9.Cu" signal "IN3")
		(22 "In10.Cu" signal "GND4")
		(24 "In11.Cu" signal "IN4")
		(26 "In12.Cu" signal "GND5")
		(28 "In13.Cu" signal "IN5")
		(30 "In14.Cu" signal "GND6")
		(32 "In15.Cu" signal "IN6")
		(34 "In16.Cu" signal "GND7")
		(2 "B.Cu" signal "BOTTOM")
		(9 "F.Adhes" user "F.Adhesive")
		(11 "B.Adhes" user "B.Adhesive")
		(13 "F.Paste" user "Package Geometry/Pastemask Top")
		(15 "B.Paste" user "Package Geometry/Pastemask Bottom")
		(5 "F.SilkS" user "Ref Des/Silkscreen Top")
		(7 "B.SilkS" user "Ref Des/Silkscreen Bottom")
		(1 "F.Mask" user "Board Geometry/Soldermask Top")
		(3 "B.Mask" user "Board Geometry/Soldermask Bottom")
		(17 "Dwgs.User" user "User.Drawings")
		(19 "Cmts.User" user "User.Comments")
		(21 "Eco1.User" user "User.Eco1")
		(23 "Eco2.User" user "User.Eco2")
		(25 "Edge.Cuts" user "Board Geometry/Outline")
		(27 "Margin" user)
		(31 "F.CrtYd" user "Package Geometry/Place Bound Top")
		(29 "B.CrtYd" user "Package Geometry/Place Bound Bottom")
		(35 "F.Fab" user "Ref Des/Assembly Top")
		(33 "B.Fab" user "Ref Des/Assembly Bottom")
	)
	(footprint ""
		(layer "F.Cu")
		(at 109.54639 -282.421584 -90)
		(property "Reference" "PC65"
			(at 0 0 270)
			(layer "F.SilkS")
			(hide yes)
			(effects
				(font
					(size 1.27 1.27)
				)
			)
		)
		(property "Value" ""
			(at 0 0 270)
			(layer "F.Fab")
			(effects
				(font
					(size 1.27 1.27)
				)
			)
		)
		(duplicate_pad_numbers_are_jumpers no)
		(fp_line
			(start -0.7874 0.4064)
			(end -0.7874 -0.4064)
			(stroke
				(width 0.1524)
				(type default)
			)
			(layer "F.SilkS")
		)
		(fp_line
			(start 0.7874 0.4064)
			(end -0.7874 0.4064)
			(stroke
				(width 0.1524)
				(type default)
			)
			(layer "F.SilkS")
		)
		(fp_line
			(start -0.7874 -0.4064)
			(end 0.7874 -0.4064)
			(stroke
				(width 0.1524)
				(type default)
			)
			(layer "F.SilkS")
		)
		(fp_line
			(start 0.7874 -0.4064)
			(end 0.7874 0.4064)
			(stroke
				(width 0.1524)
				(type default)
			)
			(layer "F.SilkS")
		)
		(fp_line
			(start -0.67945 0.3048)
			(end -0.67945 -0.305054)
			(stroke
				(width 0.1)
				(type default)
			)
			(layer "F.Fab")
		)
		(fp_line
			(start -0.12065 0.3048)
			(end -0.67945 0.3048)
			(stroke
				(width 0.1)
				(type default)
			)
			(layer "F.Fab")
		)
		(fp_line
			(start 0.120396 0.3048)
			(end 0.120396 0.2794)
			(stroke
				(width 0.1)
				(type default)
			)
			(layer "F.Fab")
		)
		(fp_line
			(start 0.67945 0.3048)
			(end 0.120396 0.3048)
			(stroke
				(width 0.1)
				(type default)
			)
			(layer "F.Fab")
		)
		(fp_line
			(start -0.12065 0.2794)
			(end -0.12065 0.3048)
			(stroke
				(width 0.1)
				(type default)
			)
			(layer "F.Fab")
		)
		(fp_line
			(start 0.120396 0.2794)
			(end -0.12065 0.2794)
			(stroke
				(width 0.1)
				(type default)
			)
			(layer "F.Fab")
		)
		(fp_line
			(start -0.12065 -0.2794)
			(end 0.12065 -0.2794)
			(stroke
				(width 0.1)
				(type default)
			)
			(layer "F.Fab")
		)
		(fp_line
			(start 0.12065 -0.2794)
			(end 0.12065 -0.3048)
			(stroke
				(width 0.1)
				(type default)
			)
			(layer "F.Fab")
		)
		(fp_line
			(start 0.12065 -0.3048)
			(end 0.67945 -0.3048)
			(stroke
				(width 0.1)
				(type default)
			)
			(layer "F.Fab")
		)
		(fp_line
			(start 0.67945 -0.3048)
			(end 0.67945 0.3048)
			(stroke
				(width 0.1)
				(type default)
			)
			(layer "F.Fab")
		)
		(fp_line
			(start -0.67945 -0.305054)
			(end -0.12065 -0.305054)
			(stroke
				(width 0.1)
				(type default)
			)
			(layer "F.Fab")
		)
		(fp_line
			(start -0.12065 -0.305054)
			(end -0.12065 -0.2794)
			(stroke
				(width 0.1)
				(type default)
			)
			(layer "F.Fab")
		)
		(pad "1" smd circle
			(at -0.40005 0 270)
			(size 0 0)
			(layers "F.Cu" "F.Mask" "F.Paste")
			(net "P0V8_PEX0_VCC1")
		)
		(pad "2" smd circle
			(at 0.40005 0 270)
			(size 0 0)
			(layers "F.Cu" "F.Mask" "F.Paste")
			(net "GND")
		)
	)
	(footprint ""
		(layer "F.Cu")
		(at 55.883556 -61.487812 180)
		(property "Reference" "R5848"
			(at 0 0 180)
			(layer "F.SilkS")
			(hide yes)
			(effects
				(font
					(size 1.27 1.27)
				)
			)
		)
		(property "Value" ""
			(at 0 0 180)
			(layer "F.Fab")
			(effects
				(font
					(size 1.27 1.27)
				)
			)
		)
		(duplicate_pad_numbers_are_jumpers no)
		(fp_line
			(start 0.7874 0.4064)
			(end -0.7874 0.4064)
			(stroke
				(width 0.1524)
				(type default)
			)
			(layer "F.SilkS")
		)
		(fp_line
			(start 0.7874 -0.4064)
			(end 0.7874 0.4064)
			(stroke
				(width 0.1524)
				(type default)
			)
			(layer "F.SilkS")
		)
		(fp_line
			(start -0.7874 0.4064)
			(end -0.7874 -0.4064)
			(stroke
				(width 0.1524)
				(type default)
			)
			(layer "F.SilkS")
		)
		(fp_line
			(start -0.7874 -0.4064)
			(end 0.7874 -0.4064)
			(stroke
				(width 0.1524)
				(type default)
			)
			(layer "F.SilkS")
		)
		(fp_line
			(start 0.67945 0.3048)
			(end 0.120396 0.3048)
			(stroke
				(width 0.1)
				(type default)
			)
			(layer "F.Fab")
		)
		(fp_line
			(start 0.67945 -0.3048)
			(end 0.67945 0.3048)
			(stroke
				(width 0.1)
				(type default)
			)
			(layer "F.Fab")
		)
		(fp_line
			(start 0.12065 -0.2794)
			(end 0.12065 -0.3048)
			(stroke
				(width 0.1)
				(type default)
			)
			(layer "F.Fab")
		)
		(fp_line
			(start 0.12065 -0.3048)
			(end 0.67945 -0.3048)
			(stroke
				(width 0.1)
				(type default)
			)
			(layer "F.Fab")
		)
		(fp_line
			(start 0.120396 0.3048)
			(end 0.120396 0.2794)
			(stroke
				(width 0.1)
				(type default)
			)
			(layer "F.Fab")
		)
		(fp_line
			(start 0.120396 0.2794)
			(end -0.12065 0.2794)
			(stroke
				(width 0.1)
				(type default)
			)
			(layer "F.Fab")
		)
		(fp_line
			(start -0.12065 0.3048)
			(end -0.67945 0.3048)
			(stroke
				(width 0.1)
				(type default)
			)
			(layer "F.Fab")
		)
		(fp_line
			(start -0.12065 0.2794)
			(end -0.12065 0.3048)
			(stroke
				(width 0.1)
				(type default)
			)
			(layer "F.Fab")
		)
		(fp_line
			(start -0.12065 -0.2794)
			(end 0.12065 -0.2794)
			(stroke
				(width 0.1)
				(type default)
			)
			(layer "F.Fab")
		)
		(fp_line
			(start -0.12065 -0.305054)
			(end -0.12065 -0.2794)
			(stroke
				(width 0.1)
				(type default)
			)
			(layer "F.Fab")
		)
		(fp_line
			(start -0.67945 0.3048)
			(end -0.67945 -0.305054)
			(stroke
				(width 0.1)
				(type default)
			)
			(layer "F.Fab")
		)
		(fp_line
			(start -0.67945 -0.305054)
			(end -0.12065 -0.305054)
			(stroke
				(width 0.1)
				(type default)
			)
			(layer "F.Fab")
		)
		(pad "1" smd circle
			(at -0.40005 0 180)
			(size 0 0)
			(layers "F.Cu" "F.Mask" "F.Paste")
			(net "PWRGD_P12V_SSD2_D")
		)
		(pad "2" smd circle
			(at 0.40005 0 180)
			(size 0 0)
			(layers "F.Cu" "F.Mask" "F.Paste")
			(net "PWRGD_P12V_SSD2_R")
		)
	)
	(footprint ""
		(layer "F.Cu")
		(at 356.934008 -156.288994 -90)
		(property "Reference" "PR7053"
			(at 0 0 270)
			(layer "F.SilkS")
			(hide yes)
			(effects
				(font
					(size 1.27 1.27)
				)
			)
		)
		(property "Value" ""
			(at 0 0 270)
			(layer "F.Fab")
			(effects
				(font
					(size 1.27 1.27)
				)
			)
		)
		(duplicate_pad_numbers_are_jumpers no)
		(fp_line
			(start -0.7874 0.4064)
			(end -0.7874 -0.4064)
			(stroke
				(width 0.1524)
				(type default)
			)
			(layer "F.SilkS")
		)
		(fp_line
			(start 0.7874 0.4064)
			(end -0.7874 0.4064)
			(stroke
				(width 0.1524)
				(type default)
			)
			(layer "F.SilkS")
		)
		(fp_line
			(start -0.7874 -0.4064)
			(end 0.7874 -0.4064)
			(stroke
				(width 0.1524)
				(type default)
			)
			(layer "F.SilkS")
		)
		(fp_line
			(start 0.7874 -0.4064)
			(end 0.7874 0.4064)
			(stroke
				(width 0.1524)
				(type default)
			)
			(layer "F.SilkS")
		)
		(fp_line
			(start -0.67945 0.3048)
			(end -0.67945 -0.305054)
			(stroke
				(width 0.1)
				(type default)
			)
			(layer "F.Fab")
		)
		(fp_line
			(start -0.12065 0.3048)
			(end -0.67945 0.3048)
			(stroke
				(width 0.1)
				(type default)
			)
			(layer "F.Fab")
		)
		(fp_line
			(start 0.120396 0.3048)
			(end 0.120396 0.2794)
			(stroke
				(width 0.1)
				(type default)
			)
			(layer "F.Fab")
		)
		(fp_line
			(start 0.67945 0.3048)
			(end 0.120396 0.3048)
			(stroke
				(width 0.1)
				(type default)
			)
			(layer "F.Fab")
		)
		(fp_line
			(start -0.12065 0.2794)
			(end -0.12065 0.3048)
			(stroke
				(width 0.1)
				(type default)
			)
			(layer "F.Fab")
		)
		(fp_line
			(start 0.120396 0.2794)
			(end -0.12065 0.2794)
			(stroke
				(width 0.1)
				(type default)
			)
			(layer "F.Fab")
		)
		(fp_line
			(start -0.12065 -0.2794)
			(end 0.12065 -0.2794)
			(stroke
				(width 0.1)
				(type default)
			)
			(layer "F.Fab")
		)
		(fp_line
			(start 0.12065 -0.2794)
			(end 0.12065 -0.3048)
			(stroke
				(width 0.1)
				(type default)
			)
			(layer "F.Fab")
		)
		(fp_line
			(start 0.12065 -0.3048)
			(end 0.67945 -0.3048)
			(stroke
				(width 0.1)
				(type default)
			)
			(layer "F.Fab")
		)
		(fp_line
			(start 0.67945 -0.3048)
			(end 0.67945 0.3048)
			(stroke
				(width 0.1)
				(type default)
			)
			(layer "F.Fab")
		)
		(fp_line
			(start -0.67945 -0.305054)
			(end -0.12065 -0.305054)
			(stroke
				(width 0.1)
				(type default)
			)
			(layer "F.Fab")
		)
		(fp_line
			(start -0.12065 -0.305054)
			(end -0.12065 -0.2794)
			(stroke
				(width 0.1)
				(type default)
			)
			(layer "F.Fab")
		)
		(pad "1" smd circle
			(at -0.40005 0 270)
			(size 0 0)
			(layers "F.Cu" "F.Mask" "F.Paste")
			(net "P12V_NIC6_CO_OV_FB")
		)
		(pad "2" smd circle
			(at 0.40005 0 270)
			(size 0 0)
			(layers "F.Cu" "F.Mask" "F.Paste")
			(net "GND")
		)
	)
	(footprint ""
		(layer "F.Cu")
		(at 91.958668 -111.227108 90)
		(property "Reference" "PC604"
			(at 0 0 90)
			(layer "F.SilkS")
			(hide yes)
			(effects
				(font
					(size 1.27 1.27)
				)
			)
		)
		(property "Value" ""
			(at 0 0 90)
			(layer "F.Fab")
			(effects
				(font
					(size 1.27 1.27)
				)
			)
		)
		(duplicate_pad_numbers_are_jumpers no)
		(fp_line
			(start 1.524 -0.762)
			(end 1.524 0.762)
			(stroke
				(width 0.1524)
				(type default)
			)
			(layer "F.SilkS")
		)
		(fp_line
			(start -1.524 -0.762)
			(end 1.524 -0.762)
			(stroke
				(width 0.1524)
				(type default)
			)
			(layer "F.SilkS")
		)
		(fp_line
			(start 1.524 0.762)
			(end -1.524 0.762)
			(stroke
				(width 0.1524)
				(type default)
			)
			(layer "F.SilkS")
		)
		(fp_line
			(start -1.524 0.762)
			(end -1.524 -0.762)
			(stroke
				(width 0.1524)
				(type default)
			)
			(layer "F.SilkS")
		)
		(fp_line
			(start 1.1049 -0.724916)
			(end -1.1049 -0.724916)
			(stroke
				(width 0.1)
				(type default)
			)
			(layer "F.Fab")
		)
		(fp_line
			(start -1.1049 -0.724916)
			(end -1.1049 0.724916)
			(stroke
				(width 0.1)
				(type default)
			)
			(layer "F.Fab")
		)
		(fp_line
			(start 1.1049 0.724916)
			(end 1.1049 -0.724916)
			(stroke
				(width 0.1)
				(type default)
			)
			(layer "F.Fab")
		)
		(fp_line
			(start -1.1049 0.724916)
			(end 1.1049 0.724916)
			(stroke
				(width 0.1)
				(type default)
			)
			(layer "F.Fab")
		)
		(pad "1" smd rect
			(at -0.889 0 270)
			(size 1.016 1.27)
			(layers "F.Cu" "F.Mask" "F.Paste")
			(net "P12V_NIC1_R")
		)
		(pad "2" smd rect
			(at 0.889 0 270)
			(size 1.016 1.27)
			(layers "F.Cu" "F.Mask" "F.Paste")
			(net "GND")
		)
	)
	(footprint ""
		(layer "F.Cu")
		(at 124.272548 -350.098614 90)
		(property "Reference" "C368"
			(at 0 0 90)
			(layer "F.SilkS")
			(hide yes)
			(effects
				(font
					(size 1.27 1.27)
				)
			)
		)
		(property "Value" ""
			(at 0 0 90)
			(layer "F.Fab")
			(effects
				(font
					(size 1.27 1.27)
				)
			)
		)
		(duplicate_pad_numbers_are_jumpers no)
		(fp_line
			(start 0.299974 -0.150114)
			(end 0.299974 0.150114)
			(stroke
				(width 0.1)
				(type default)
			)
			(layer "F.Fab")
		)
		(fp_line
			(start -0.299974 -0.150114)
			(end 0.299974 -0.150114)
			(stroke
				(width 0.1)
				(type default)
			)
			(layer "F.Fab")
		)
		(fp_line
			(start 0.299974 0.150114)
			(end -0.299974 0.150114)
			(stroke
				(width 0.1)
				(type default)
			)
			(layer "F.Fab")
		)
		(fp_line
			(start -0.299974 0.150114)
			(end -0.299974 -0.150114)
			(stroke
				(width 0.1)
				(type default)
			)
			(layer "F.Fab")
		)
		(pad "1" smd rect
			(at -0.2667 0 90)
			(size 0.3048 0.381)
			(layers "F.Cu" "F.Mask" "F.Paste")
			(net "P5E_PEX1_STN6_TX_DP<97>")
		)
		(pad "2" smd rect
			(at 0.2667 0 90)
			(size 0.3048 0.381)
			(layers "F.Cu" "F.Mask" "F.Paste")
			(net "P5E_PEX1_STN6_TX_C_DP<97>")
		)
	)
	(footprint ""
		(layer "F.Cu")
		(at 446.972944 -22.867366 90)
		(property "Reference" "C3977"
			(at 0 0 90)
			(layer "F.SilkS")
			(hide yes)
			(effects
				(font
					(size 1.27 1.27)
				)
			)
		)
		(property "Value" ""
			(at 0 0 90)
			(layer "F.Fab")
			(effects
				(font
					(size 1.27 1.27)
				)
			)
		)
		(duplicate_pad_numbers_are_jumpers no)
		(fp_line
			(start 0.7874 -0.4064)
			(end 0.7874 0.4064)
			(stroke
				(width 0.1524)
				(type default)
			)
			(layer "F.SilkS")
		)
		(fp_line
			(start -0.7874 -0.4064)
			(end 0.7874 -0.4064)
			(stroke
				(width 0.1524)
				(type default)
			)
			(layer "F.SilkS")
		)
		(fp_line
			(start 0.7874 0.4064)
			(end -0.7874 0.4064)
			(stroke
				(width 0.1524)
				(type default)
			)
			(layer "F.SilkS")
		)
		(fp_line
			(start -0.7874 0.4064)
			(end -0.7874 -0.4064)
			(stroke
				(width 0.1524)
				(type default)
			)
			(layer "F.SilkS")
		)
		(fp_line
			(start -0.12065 -0.305054)
			(end -0.12065 -0.2794)
			(stroke
				(width 0.1)
				(type default)
			)
			(layer "F.Fab")
		)
		(fp_line
			(start -0.67945 -0.305054)
			(end -0.12065 -0.305054)
			(stroke
				(width 0.1)
				(type default)
			)
			(layer "F.Fab")
		)
		(fp_line
			(start 0.67945 -0.3048)
			(end 0.67945 0.3048)
			(stroke
				(width 0.1)
				(type default)
			)
			(layer "F.Fab")
		)
		(fp_line
			(start 0.12065 -0.3048)
			(end 0.67945 -0.3048)
			(stroke
				(width 0.1)
				(type default)
			)
			(layer "F.Fab")
		)
		(fp_line
			(start 0.12065 -0.2794)
			(end 0.12065 -0.3048)
			(stroke
				(width 0.1)
				(type default)
			)
			(layer "F.Fab")
		)
		(fp_line
			(start -0.12065 -0.2794)
			(end 0.12065 -0.2794)
			(stroke
				(width 0.1)
				(type default)
			)
			(layer "F.Fab")
		)
		(fp_line
			(start 0.120396 0.2794)
			(end -0.12065 0.2794)
			(stroke
				(width 0.1)
				(type default)
			)
			(layer "F.Fab")
		)
		(fp_line
			(start -0.12065 0.2794)
			(end -0.12065 0.3048)
			(stroke
				(width 0.1)
				(type default)
			)
			(layer "F.Fab")
		)
		(fp_line
			(start 0.67945 0.3048)
			(end 0.120396 0.3048)
			(stroke
				(width 0.1)
				(type default)
			)
			(layer "F.Fab")
		)
		(fp_line
			(start 0.120396 0.3048)
			(end 0.120396 0.2794)
			(stroke
				(width 0.1)
				(type default)
			)
			(layer "F.Fab")
		)
		(fp_line
			(start -0.12065 0.3048)
			(end -0.67945 0.3048)
			(stroke
				(width 0.1)
				(type default)
			)
			(layer "F.Fab")
		)
		(fp_line
			(start -0.67945 0.3048)
			(end -0.67945 -0.305054)
			(stroke
				(width 0.1)
				(type default)
			)
			(layer "F.Fab")
		)
		(pad "1" smd circle
			(at -0.40005 0 90)
			(size 0 0)
			(layers "F.Cu" "F.Mask" "F.Paste")
			(net "P12V_SSD15")
		)
		(pad "2" smd circle
			(at 0.40005 0 90)
			(size 0 0)
			(layers "F.Cu" "F.Mask" "F.Paste")
			(net "GND")
		)
	)
	(footprint ""
		(layer "F.Cu")
		(at 249.20575 -86.098888 180)
		(property "Reference" "R1051"
			(at 0 0 180)
			(layer "F.SilkS")
			(hide yes)
			(effects
				(font
					(size 1.27 1.27)
				)
			)
		)
		(property "Value" ""
			(at 0 0 180)
			(layer "F.Fab")
			(effects
				(font
					(size 1.27 1.27)
				)
			)
		)
		(duplicate_pad_numbers_are_jumpers no)
		(fp_line
			(start 0.7874 0.4064)
			(end -0.7874 0.4064)
			(stroke
				(width 0.1524)
				(type default)
			)
			(layer "F.SilkS")
		)
		(fp_line
			(start 0.7874 -0.4064)
			(end 0.7874 0.4064)
			(stroke
				(width 0.1524)
				(type default)
			)
			(layer "F.SilkS")
		)
		(fp_line
			(start -0.7874 0.4064)
			(end -0.7874 -0.4064)
			(stroke
				(width 0.1524)
				(type default)
			)
			(layer "F.SilkS")
		)
		(fp_line
			(start -0.7874 -0.4064)
			(end 0.7874 -0.4064)
			(stroke
				(width 0.1524)
				(type default)
			)
			(layer "F.SilkS")
		)
		(fp_line
			(start 0.67945 0.3048)
			(end 0.120396 0.3048)
			(stroke
				(width 0.1)
				(type default)
			)
			(layer "F.Fab")
		)
		(fp_line
			(start 0.67945 -0.3048)
			(end 0.67945 0.3048)
			(stroke
				(width 0.1)
				(type default)
			)
			(layer "F.Fab")
		)
		(fp_line
			(start 0.12065 -0.2794)
			(end 0.12065 -0.3048)
			(stroke
				(width 0.1)
				(type default)
			)
			(layer "F.Fab")
		)
		(fp_line
			(start 0.12065 -0.3048)
			(end 0.67945 -0.3048)
			(stroke
				(width 0.1)
				(type default)
			)
			(layer "F.Fab")
		)
		(fp_line
			(start 0.120396 0.3048)
			(end 0.120396 0.2794)
			(stroke
				(width 0.1)
				(type default)
			)
			(layer "F.Fab")
		)
		(fp_line
			(start 0.120396 0.2794)
			(end -0.12065 0.2794)
			(stroke
				(width 0.1)
				(type default)
			)
			(layer "F.Fab")
		)
		(fp_line
			(start -0.12065 0.3048)
			(end -0.67945 0.3048)
			(stroke
				(width 0.1)
				(type default)
			)
			(layer "F.Fab")
		)
		(fp_line
			(start -0.12065 0.2794)
			(end -0.12065 0.3048)
			(stroke
				(width 0.1)
				(type default)
			)
			(layer "F.Fab")
		)
		(fp_line
			(start -0.12065 -0.2794)
			(end 0.12065 -0.2794)
			(stroke
				(width 0.1)
				(type default)
			)
			(layer "F.Fab")
		)
		(fp_line
			(start -0.12065 -0.305054)
			(end -0.12065 -0.2794)
			(stroke
				(width 0.1)
				(type default)
			)
			(layer "F.Fab")
		)
		(fp_line
			(start -0.67945 0.3048)
			(end -0.67945 -0.305054)
			(stroke
				(width 0.1)
				(type default)
			)
			(layer "F.Fab")
		)
		(fp_line
			(start -0.67945 -0.305054)
			(end -0.12065 -0.305054)
			(stroke
				(width 0.1)
				(type default)
			)
			(layer "F.Fab")
		)
		(pad "1" smd circle
			(at -0.40005 0 180)
			(size 0 0)
			(layers "F.Cu" "F.Mask" "F.Paste")
			(net "CLK_CK440_SMB_ADDR1")
		)
		(pad "2" smd circle
			(at 0.40005 0 180)
			(size 0 0)
			(layers "F.Cu" "F.Mask" "F.Paste")
			(net "P3V3")
		)
	)
)
